FILE_TYPE=LIBRARY_PARTS;
primitive 'PI7C9X1172','PI7C9X1172_QFN';
  pin
    'A0_CS_N':
      PIN_NUMBER='(30)';
      INPUT_LOAD='(-0.01,0.01)';
    'A1_S1':
      PIN_NUMBER='(31)';
      INPUT_LOAD='(-0.01,0.01)';
    'CTSA_N':
      PIN_NUMBER='(25)';
      INPUT_LOAD='(-0.01,0.01)';
    'CTSB_N':
      PIN_NUMBER='(16)';
      INPUT_LOAD='(-0.01,0.01)';
    'EN485_N':
      PIN_NUMBER='(19)';
      INPUT_LOAD='(-0.01,0.01)';
    'ENIR_N':
      PIN_NUMBER='(18)';
      INPUT_LOAD='(-0.01,0.01)';
    'GND':
      PIN_NUMBER='(12)';
      PINUSE='GROUND';
      NO_LOAD_CHECK='Both';
      NO_IO_CHECK='Both';
      NO_ASSERT_CHECK='TRUE';
      NO_DIR_CHECK='TRUE';
      ALLOW_CONNECT='TRUE';
    'GPIO0_DSRB_N':
      PIN_NUMBER='(13)';
      BIDIRECTIONAL='TRUE';
      INPUT_LOAD='(-0.01,0.01)';
      OUTPUT_LOAD='(1.0,-1.0)';
    'GPIO1_DTRB_N':
      PIN_NUMBER='(23)';
      BIDIRECTIONAL='TRUE';
      INPUT_LOAD='(-0.01,0.01)';
      OUTPUT_LOAD='(1.0,-1.0)';
    'GPIO2_CDB_N':
      PIN_NUMBER='(11)';
      BIDIRECTIONAL='TRUE';
      INPUT_LOAD='(-0.01,0.01)';
      OUTPUT_LOAD='(1.0,-1.0)';
    'GPIO3_RIB_N':
      PIN_NUMBER='(14)';
      BIDIRECTIONAL='TRUE';
      INPUT_LOAD='(-0.01,0.01)';
      OUTPUT_LOAD='(1.0,-1.0)';
    'GPIO4_DSRA_N':
      PIN_NUMBER='(26)';
      BIDIRECTIONAL='TRUE';
      INPUT_LOAD='(-0.01,0.01)';
      OUTPUT_LOAD='(1.0,-1.0)';
    'GPIO5_DTRA_N':
      PIN_NUMBER='(22)';
      BIDIRECTIONAL='TRUE';
      INPUT_LOAD='(-0.01,0.01)';
      OUTPUT_LOAD='(1.0,-1.0)';
    'GPIO6_CDA_N':
      PIN_NUMBER='(27)';
      BIDIRECTIONAL='TRUE';
      INPUT_LOAD='(-0.01,0.01)';
      OUTPUT_LOAD='(1.0,-1.0)';
    'GPIO7_RIA_N':
      PIN_NUMBER='(28)';
      BIDIRECTIONAL='TRUE';
      INPUT_LOAD='(-0.01,0.01)';
      OUTPUT_LOAD='(1.0,-1.0)';
    'I2C_SPI_N':
      PIN_NUMBER='(32)';
      INPUT_LOAD='(-0.01,0.01)';
    'IRQ_N':
      PIN_NUMBER='(20)';
      OUTPUT_LOAD='(1.0,-1.0)';
    'NC'<1>:
      PIN_NUMBER='(8)';
      PINUSE='NC';
      NO_LOAD_CHECK='Both';
      NO_IO_CHECK='Both';
      NO_ASSERT_CHECK='TRUE';
      NO_DIR_CHECK='TRUE';
      ALLOW_CONNECT='TRUE';
    'NC'<0>:
      PIN_NUMBER='(1)';
      PINUSE='NC';
      NO_LOAD_CHECK='Both';
      NO_IO_CHECK='Both';
      NO_ASSERT_CHECK='TRUE';
      NO_DIR_CHECK='TRUE';
      ALLOW_CONNECT='TRUE';
    'RESET_N':
      PIN_NUMBER='(24)';
      INPUT_LOAD='(-0.01,0.01)';
    'RTSA_N':
      PIN_NUMBER='(21)';
      OUTPUT_LOAD='(1.0,-1.0)';
    'RTSB_N':
      PIN_NUMBER='(15)';
      OUTPUT_LOAD='(1.0,-1.0)';
    'RXA':
      PIN_NUMBER='(5)';
      INPUT_LOAD='(-0.01,0.01)';
    'RXB':
      PIN_NUMBER='(4)';
      INPUT_LOAD='(-0.01,0.01)';
    'SCL':
      PIN_NUMBER='(17)';
      INPUT_LOAD='(-0.01,0.01)';
    'SDA':
      PIN_NUMBER='(3)';
      BIDIRECTIONAL='TRUE';
      INPUT_LOAD='(-0.01,0.01)';
      OUTPUT_LOAD='(1.0,-1.0)';
    'SO':
      PIN_NUMBER='(2)';
      OUTPUT_LOAD='(1.0,-1.0)';
    'THPAD':
      PIN_NUMBER='(33)';
      PINUSE='GROUND';
      NO_LOAD_CHECK='Both';
      NO_IO_CHECK='Both';
      NO_ASSERT_CHECK='TRUE';
      NO_DIR_CHECK='TRUE';
      ALLOW_CONNECT='TRUE';
    'TXA':
      PIN_NUMBER='(6)';
      OUTPUT_LOAD='(1.0,-1.0)';
    'TXB':
      PIN_NUMBER='(7)';
      OUTPUT_LOAD='(1.0,-1.0)';
    'VDD':
      PIN_NUMBER='(29)';
      PINUSE='POWER';
      NO_LOAD_CHECK='Both';
      NO_IO_CHECK='Both';
      NO_ASSERT_CHECK='TRUE';
      NO_DIR_CHECK='TRUE';
      ALLOW_CONNECT='TRUE';
    'XTAL1':
      PIN_NUMBER='(9)';
      INPUT_LOAD='(-0.01,0.01)';
    'XTAL2':
      PIN_NUMBER='(10)';
      OUTPUT_LOAD='(1.0,-1.0)';
  end_pin;
  body
    PART_NAME='PI7C9X1172';
    PHYS_DES_PREFIX='EU';
  end_body;
end_primitive;

END.
